FILE_TYPE = CONNECTIVITY;
{Allegro Design Entry HDL 17.2-2016 S081 (4005846) 1/11/2022}
"PAGE_NUMBER" = 179;
0"NC";
END.
